(kicad_pcb
	(version 20241229)
	(generator "pcbnew")
	(generator_version "9.0")
	(general
		(thickness 1.63)
		(legacy_teardrops no)
	)
	(paper "A4")
	(title_block
		(title "CM4 Baseboard")
		(date "2026-01-05")
		(rev "1.1.1")
		(company "Antmicro Ltd")
		(comment 1 "www.antmicro.com")
		(comment 9 "footprints 313-316 of 506")
	)
	(layers
		(0 "F.Cu" signal)
		(4 "In1.Cu" power)
		(6 "In2.Cu" power)
		(8 "In3.Cu" signal)
		(10 "In4.Cu" signal)
		(2 "B.Cu" signal)
		(9 "F.Adhes" user "F.Adhesive")
		(11 "B.Adhes" user "B.Adhesive")
		(13 "F.Paste" user)
		(15 "B.Paste" user)
		(5 "F.SilkS" user "F.Silkscreen")
		(7 "B.SilkS" user "B.Silkscreen")
		(1 "F.Mask" user)
		(3 "B.Mask" user)
		(17 "Dwgs.User" user "User.Drawings")
		(19 "Cmts.User" user "User.Comments")
		(21 "Eco1.User" user "User.Eco1")
		(23 "Eco2.User" user "User.Eco2")
		(25 "Edge.Cuts" user)
		(27 "Margin" user)
		(31 "F.CrtYd" user "F.Courtyard")
		(29 "B.CrtYd" user "B.Courtyard")
		(35 "F.Fab" user)
		(33 "B.Fab" user)
	)
	(footprint "antmicro-footprints:C_0402_1005Metric"
		(layer "F.Cu")
		(at 72.717962 176.6665 90)
		(descr "Capacitor SMD 0402")
		(tags "capacitor SMD 0402")
		(property "Reference" "C801"
			(at -2.83 -1.73 180)
			(layer "F.SilkS")
			(effects
				(font
					(size 0.7 0.7)
					(thickness 0.15)
				)
				(justify left bottom)
			)
		)
		(property "Value" "C_4u7_0402"
			(at -1.022927 2.155213 90)
			(layer "F.Fab")
			(effects
				(font
					(size 0.7 0.7)
					(thickness 0.15)
				)
				(justify left bottom)
			)
		)
		(property "Datasheet" "https://www.murata.com/products/productdetail?partno=GRM155R61A475MEAA%23"
			(at 0 0 90)
			(layer "F.Fab")
			(hide yes)
			(effects
				(font
					(size 1.27 1.27)
					(thickness 0.15)
				)
			)
		)
		(property "MPN" "GRM155R61A475MEAAD"
			(at 0 0 90)
			(unlocked yes)
			(layer "F.Fab")
			(hide yes)
			(effects
				(font
					(size 1 1)
					(thickness 0.15)
				)
			)
		)
		(property "Manufacturer" "Murata"
			(at 0 0 90)
			(unlocked yes)
			(layer "F.Fab")
			(hide yes)
			(effects
				(font
					(size 1 1)
					(thickness 0.15)
				)
			)
		)
		(property "License" "Apache-2.0"
			(at 0 0 90)
			(unlocked yes)
			(layer "F.Fab")
			(hide yes)
			(effects
				(font
					(size 1 1)
					(thickness 0.15)
				)
			)
		)
		(property "Author" "Antmicro"
			(at 0 0 90)
			(unlocked yes)
			(layer "F.Fab")
			(hide yes)
			(effects
				(font
					(size 1 1)
					(thickness 0.15)
				)
			)
		)
		(property "Val" "4u7"
			(at 0 0 90)
			(unlocked yes)
			(layer "F.Fab")
			(hide yes)
			(effects
				(font
					(size 1 1)
					(thickness 0.15)
				)
			)
		)
		(property "Voltage" ""
			(at 0 0 90)
			(unlocked yes)
			(layer "F.Fab")
			(hide yes)
			(effects
				(font
					(size 1 1)
					(thickness 0.15)
				)
			)
		)
		(property "Dielectric" ""
			(at 0 0 90)
			(unlocked yes)
			(layer "F.Fab")
			(hide yes)
			(effects
				(font
					(size 1 1)
					(thickness 0.15)
				)
			)
		)
		(sheetname "/Peripherals/")
		(sheetfile "peripherals.kicad_sch")
		(attr smd)
		(fp_rect
			(start -0.925 -0.47)
			(end 0.925 0.47)
			(stroke
				(width 0.05)
				(type default)
			)
			(fill no)
			(layer "F.CrtYd")
		)
		(fp_line
			(start 0.504 -0.25)
			(end 0.504 0.248)
			(stroke
				(width 0.15)
				(type solid)
			)
			(layer "F.Fab")
		)
		(fp_line
			(start -0.494 -0.25)
			(end 0.504 -0.25)
			(stroke
				(width 0.15)
				(type solid)
			)
			(layer "F.Fab")
		)
		(fp_line
			(start 0.504 0.248)
			(end -0.494 0.248)
			(stroke
				(width 0.15)
				(type solid)
			)
			(layer "F.Fab")
		)
		(fp_line
			(start -0.494 0.248)
			(end -0.494 -0.25)
			(stroke
				(width 0.15)
				(type solid)
			)
			(layer "F.Fab")
		)
		(fp_text user "License: Apache-2.0"
			(at -0.939 5.799 90)
			(layer "F.Fab")
			(effects
				(font
					(size 0.7 0.7)
					(thickness 0.15)
				)
				(justify left bottom)
			)
		)
		(fp_text user "${REFERENCE}"
			(at -0.939 4.599 90)
			(layer "F.Fab")
			(effects
				(font
					(size 0.7 0.7)
					(thickness 0.15)
				)
				(justify left bottom)
			)
		)
		(fp_text user "Author: Antmicro"
			(at -0.939 3.399 90)
			(layer "F.Fab")
			(effects
				(font
					(size 0.7 0.7)
					(thickness 0.15)
				)
				(justify left bottom)
			)
		)
		(pad "1" smd roundrect
			(at -0.48 0 90)
			(size 0.59 0.64)
			(layers "F.Cu" "F.Mask" "F.Paste")
			(roundrect_rratio 0.25)
			(net 3 "GND")
			(pintype "passive")
		)
		(pad "2" smd roundrect
			(at 0.48 0 90)
			(size 0.59 0.64)
			(layers "F.Cu" "F.Mask" "F.Paste")
			(roundrect_rratio 0.25)
			(net 501 "Net-(U801-V_{DD(UP)})")
			(pintype "passive")
		)
	)
	(footprint "antmicro-footprints:TP_SMD_0.75mm"
		(layer "F.Cu")
		(at 108.867962 147.4665)
		(property "Reference" "TP215"
			(at 1.35 0.35 90)
			(layer "F.SilkS")
			(effects
				(font
					(size 0.7 0.7)
					(thickness 0.15)
				)
				(justify left bottom)
			)
		)
		(property "Value" "TP_0.75mm_SMD"
			(at 0 1.2 0)
			(layer "F.Fab")
			(effects
				(font
					(size 0.7 0.7)
					(thickness 0.15)
				)
				(justify left bottom)
			)
		)
		(property "MPN" ""
			(at 0 0 0)
			(unlocked yes)
			(layer "F.Fab")
			(hide yes)
			(effects
				(font
					(size 1 1)
					(thickness 0.15)
				)
			)
		)
		(property "Manufacturer" ""
			(at 0 0 0)
			(unlocked yes)
			(layer "F.Fab")
			(hide yes)
			(effects
				(font
					(size 1 1)
					(thickness 0.15)
				)
			)
		)
		(property "Author" "Antmicro"
			(at 0 0 0)
			(unlocked yes)
			(layer "F.Fab")
			(hide yes)
			(effects
				(font
					(size 1 1)
					(thickness 0.15)
				)
			)
		)
		(property "License" "Apache-2.0"
			(at 0 0 0)
			(unlocked yes)
			(layer "F.Fab")
			(hide yes)
			(effects
				(font
					(size 1 1)
					(thickness 0.15)
				)
			)
		)
		(sheetname "/Compute module/")
		(sheetfile "compute-module.kicad_sch")
		(attr exclude_from_pos_files exclude_from_bom)
		(fp_circle
			(center 0 0)
			(end 0.475 0)
			(stroke
				(width 0.05)
				(type default)
			)
			(fill no)
			(layer "F.CrtYd")
		)
		(fp_text user "License: Apache-2.0"
			(at -0.4 5.101 0)
			(layer "F.Fab")
			(effects
				(font
					(size 0.7 0.7)
					(thickness 0.15)
				)
				(justify left bottom)
			)
		)
		(fp_text user "Author: Antmicro"
			(at -0.4 3.901 0)
			(layer "F.Fab")
			(effects
				(font
					(size 0.7 0.7)
					(thickness 0.15)
				)
				(justify left bottom)
			)
		)
		(fp_text user "${REFERENCE}"
			(at -0.4 2.7 0)
			(layer "F.Fab")
			(effects
				(font
					(size 0.7 0.7)
					(thickness 0.15)
				)
				(justify left bottom)
			)
		)
		(pad "1" smd circle
			(at 0 0)
			(size 0.75 0.75)
			(layers "F.Cu" "F.Mask")
			(net 258 "/Compute module/Pf_5V.SDA")
			(pinfunction "1")
			(pintype "passive")
		)
	)
	(footprint "antmicro-footprints:TP_SMD_0.75mm"
		(layer "F.Cu")
		(at 75.75 169.5 -90)
		(property "Reference" "TP802"
			(at -1.76 -8.225 0)
			(layer "F.SilkS")
			(effects
				(font
					(size 0.7 0.7)
					(thickness 0.15)
				)
				(justify left bottom)
			)
		)
		(property "Value" "TP_0.75mm_SMD"
			(at 0 1.2 270)
			(layer "F.Fab")
			(effects
				(font
					(size 0.7 0.7)
					(thickness 0.15)
				)
				(justify left bottom)
			)
		)
		(property "Author" "Antmicro"
			(at 0 0 270)
			(unlocked yes)
			(layer "F.Fab")
			(hide yes)
			(effects
				(font
					(size 1 1)
					(thickness 0.15)
				)
			)
		)
		(property "License" "Apache-2.0"
			(at 0 0 270)
			(unlocked yes)
			(layer "F.Fab")
			(hide yes)
			(effects
				(font
					(size 1 1)
					(thickness 0.15)
				)
			)
		)
		(property "MPN" ""
			(at 0 0 270)
			(unlocked yes)
			(layer "F.Fab")
			(hide yes)
			(effects
				(font
					(size 1 1)
					(thickness 0.15)
				)
			)
		)
		(property "Manufacturer" ""
			(at 0 0 270)
			(unlocked yes)
			(layer "F.Fab")
			(hide yes)
			(effects
				(font
					(size 1 1)
					(thickness 0.15)
				)
			)
		)
		(sheetname "/Peripherals/")
		(sheetfile "peripherals.kicad_sch")
		(attr exclude_from_pos_files exclude_from_bom)
		(fp_circle
			(center 0 0)
			(end 0.475 0)
			(stroke
				(width 0.05)
				(type default)
			)
			(fill no)
			(layer "F.CrtYd")
		)
		(fp_text user "License: Apache-2.0"
			(at -0.4 5.101 270)
			(layer "F.Fab")
			(effects
				(font
					(size 0.7 0.7)
					(thickness 0.15)
				)
				(justify left bottom)
			)
		)
		(fp_text user "Author: Antmicro"
			(at -0.4 3.901 270)
			(layer "F.Fab")
			(effects
				(font
					(size 0.7 0.7)
					(thickness 0.15)
				)
				(justify left bottom)
			)
		)
		(fp_text user "${REFERENCE}"
			(at -0.4 2.7 270)
			(layer "F.Fab")
			(effects
				(font
					(size 0.7 0.7)
					(thickness 0.15)
				)
				(justify left bottom)
			)
		)
		(pad "1" smd circle
			(at 0 0 270)
			(size 0.75 0.75)
			(layers "F.Cu" "F.Mask")
			(net 382 "Net-(U801-CLK_REQ)")
			(pinfunction "1")
			(pintype "passive")
		)
	)
	(footprint "antmicro-footprints:L_TE_0603_1811Metric"
		(layer "F.Cu")
		(at 66.74 174.05 180)
		(property "Reference" "L802"
			(at 1.64 1 0)
			(layer "F.SilkS")
			(effects
				(font
					(size 0.7 0.7)
					(thickness 0.15)
				)
				(justify right top)
			)
		)
		(property "Value" "L_160n_0.28A_0603"
			(at -1.41 1.759999 0)
			(layer "F.Fab")
			(effects
				(font
					(size 0.7 0.7)
					(thickness 0.15)
				)
				(justify right top)
			)
		)
		(property "Datasheet" "https://www.te.com/commerce/DocumentDelivery/DDEController?Action=showdoc&DocId=Data+Sheet%7F1773163%7FE%7Fpdf%7FEnglish%7FENG_DS_1773163_E.pdf"
			(at 0 0 0)
			(layer "F.Fab")
			(effects
				(font
					(size 0.7 0.7)
					(thickness 0.15)
				)
				(justify right top)
			)
		)
		(property "Description" "RF Inductor - 160 nH, 5%, 280 mA, 0603"
			(at 0 0 0)
			(layer "F.Fab")
			(effects
				(font
					(size 0.7 0.7)
					(thickness 0.15)
				)
				(justify right top)
			)
		)
		(property "Val" "160 nH"
			(at 0 0 180)
			(unlocked yes)
			(layer "F.Fab")
			(hide yes)
			(effects
				(font
					(size 1 1)
					(thickness 0.15)
				)
			)
		)
		(property "Manufacturer" "TE Connectivity"
			(at 0 0 180)
			(unlocked yes)
			(layer "F.Fab")
			(hide yes)
			(effects
				(font
					(size 1 1)
					(thickness 0.15)
				)
			)
		)
		(property "MPN" "36501JR16JTDG"
			(at 0 0 180)
			(unlocked yes)
			(layer "F.Fab")
			(hide yes)
			(effects
				(font
					(size 1 1)
					(thickness 0.15)
				)
			)
		)
		(property "ISat" ""
			(at 0 0 180)
			(unlocked yes)
			(layer "F.Fab")
			(hide yes)
			(effects
				(font
					(size 1 1)
					(thickness 0.15)
				)
			)
		)
		(property "IMax" "0.28 A"
			(at 0 0 180)
			(unlocked yes)
			(layer "F.Fab")
			(hide yes)
			(effects
				(font
					(size 1 1)
					(thickness 0.15)
				)
			)
		)
		(property "Size" "1.8 x 1.12"
			(at 0 0 180)
			(unlocked yes)
			(layer "F.Fab")
			(hide yes)
			(effects
				(font
					(size 1 1)
					(thickness 0.15)
				)
			)
		)
		(property "Author" "Antmicro"
			(at 0 0 180)
			(unlocked yes)
			(layer "F.Fab")
			(hide yes)
			(effects
				(font
					(size 1 1)
					(thickness 0.15)
				)
			)
		)
		(property "License" "Apache-2.0"
			(at 0 0 180)
			(unlocked yes)
			(layer "F.Fab")
			(hide yes)
			(effects
				(font
					(size 1 1)
					(thickness 0.15)
				)
			)
		)
		(sheetname "/Peripherals/")
		(sheetfile "peripherals.kicad_sch")
		(attr smd)
		(fp_line
			(start -0.15 0.4)
			(end 0.15 0.4)
			(stroke
				(width 0.15)
				(type solid)
			)
			(layer "F.SilkS")
		)
		(fp_line
			(start -0.15 -0.4)
			(end 0.15 -0.4)
			(stroke
				(width 0.15)
				(type solid)
			)
			(layer "F.SilkS")
		)
		(fp_poly
			(pts
				(xy -1.06 -0.66) (xy 1.06 -0.66) (xy 1.06 0.66) (xy -1.06 0.66)
			)
			(stroke
				(width 0.05)
				(type solid)
			)
			(fill no)
			(layer "F.CrtYd")
		)
		(fp_poly
			(pts
				(xy -0.8 -0.4) (xy 0.8 -0.4) (xy 0.8 0.4) (xy -0.8 0.4)
			)
			(stroke
				(width 0.15)
				(type solid)
			)
			(fill no)
			(layer "F.Fab")
		)
		(fp_text user "Author: Antmicro"
			(at -1.41 4.16 0)
			(layer "F.Fab")
			(effects
				(font
					(size 0.7 0.7)
					(thickness 0.15)
				)
				(justify right top)
			)
		)
		(fp_text user "License: Apache-2.0"
			(at -1.41 5.36 0)
			(layer "F.Fab")
			(effects
				(font
					(size 0.7 0.7)
					(thickness 0.15)
				)
				(justify right top)
			)
		)
		(fp_text user "${REFERENCE}"
			(at -1.41 2.960001 0)
			(layer "F.Fab")
			(effects
				(font
					(size 0.7 0.7)
					(thickness 0.15)
				)
				(justify right top)
			)
		)
		(pad "1" smd roundrect
			(at -0.64 0 180)
			(size 0.64 1.02)
			(layers "F.Cu" "F.Mask" "F.Paste")
			(roundrect_rratio 0.2)
			(net 326 "Net-(U801-TX2)")
			(pintype "passive")
		)
		(pad "2" smd roundrect
			(at 0.64 0 180)
			(size 0.64 1.02)
			(layers "F.Cu" "F.Mask" "F.Paste")
			(roundrect_rratio 0.2)
			(net 110 "Net-(C817-Pad1)")
			(pintype "passive")
		)
	)
)
